# BASEBOARD_FAB2 (Tioga Pass) — schematic netlist excerpt (pin names and nets, part order shuffled) for the footprints in the layout excerpt that follows; sources: Cadence DE-HDL packaged netlist, KiCad conversion of Wiwynn_Tioga_Pass_MB.brd

R7F3  RES  33.2 1% CHIP  pkg 0402  page 153 : A = SPI_BIOS_SOCKET_IO3 ; B = PU_BIOS_SPI_HOLD0_N
C5D51  CAP_A  22.0UF 4V 20% X6S  pkg 0603V  page 42 : A = PVCCMCP_CPU0 ; B = GND
R8E22  RES  4.75K 1% CHIP  pkg 0402  page 156 : A = P3V3_STBY ; B = IRQ_BMC_PCH_NMI_STBY_N

(kicad_pcb
	(version 20260206)
	(generator "pcbnew")
	(generator_version "10.0")
	(general
		(thickness 1.6)
		(legacy_teardrops no)
	)
	(paper "A4")
	(title_block
		(title "Wiwynn_Tioga_Pass_MB.brd")
		(comment 1 "Tioga Pass / footprints 1370-1372 of 4770")
	)
	(layers
		(0 "F.Cu" signal "TOP")
		(4 "In1.Cu" signal "L2GND")
		(6 "In2.Cu" signal "L3")
		(8 "In3.Cu" signal "L4GND")
		(10 "In4.Cu" signal "L5")
		(12 "In5.Cu" signal "L6GND")
		(14 "In6.Cu" signal "L7VCC")
		(16 "In7.Cu" signal "L8VCC")
		(18 "In8.Cu" signal "L9GND")
		(20 "In9.Cu" signal "L10")
		(22 "In10.Cu" signal "L11GND")
		(24 "In11.Cu" signal "L12")
		(26 "In12.Cu" signal "L13GND")
		(2 "B.Cu" signal "BOTTOM")
		(9 "F.Adhes" user "F.Adhesive")
		(11 "B.Adhes" user "B.Adhesive")
		(13 "F.Paste" user "Package Geometry/Pastemask Top")
		(15 "B.Paste" user "Package Geometry/Pastemask Bottom")
		(5 "F.SilkS" user "Ref Des/Silkscreen Top")
		(7 "B.SilkS" user "Ref Des/Silkscreen Bottom")
		(1 "F.Mask" user "Board Geometry/Soldermask Top")
		(3 "B.Mask" user "Board Geometry/Soldermask Bottom")
		(17 "Dwgs.User" user "User.Drawings")
		(19 "Cmts.User" user "User.Comments")
		(21 "Eco1.User" user "User.Eco1")
		(23 "Eco2.User" user "User.Eco2")
		(25 "Edge.Cuts" user "Board Geometry/Outline")
		(27 "Margin" user)
		(31 "F.CrtYd" user "Package Geometry/Place Bound Top")
		(29 "B.CrtYd" user "Package Geometry/Place Bound Bottom")
		(35 "F.Fab" user "Ref Des/Assembly Top")
		(33 "B.Fab" user "Ref Des/Assembly Bottom")
	)
	(footprint ""
		(layer "F.Cu")
		(at 412.4325 -109.728 90)
		(property "Reference" "R8E22"
			(at 0 0 90)
			(layer "F.SilkS")
			(hide yes)
			(effects
				(font
					(size 1.27 1.27)
				)
			)
		)
		(property "Value" ""
			(at 0 0 90)
			(layer "F.Fab")
			(effects
				(font
					(size 1.27 1.27)
				)
			)
		)
		(duplicate_pad_numbers_are_jumpers no)
		(fp_poly
			(pts
				(xy -0.2794 -0.1016) (xy 0.2794 -0.1016) (xy 0.2794 0.9906) (xy -0.2794 0.9906)
			)
			(stroke
				(width 0)
				(type default)
			)
			(fill no)
			(layer "F.CrtYd")
		)
		(fp_line
			(start 0.2794 -0.1016)
			(end -0.2794 -0.1016)
			(stroke
				(width 0.1)
				(type default)
			)
			(layer "F.Fab")
		)
		(fp_line
			(start -0.2794 -0.1016)
			(end -0.2794 0.9906)
			(stroke
				(width 0.1)
				(type default)
			)
			(layer "F.Fab")
		)
		(fp_line
			(start 0.2794 0.9906)
			(end 0.2794 -0.1016)
			(stroke
				(width 0.1)
				(type default)
			)
			(layer "F.Fab")
		)
		(fp_line
			(start -0.2794 0.9906)
			(end 0.2794 0.9906)
			(stroke
				(width 0.1)
				(type default)
			)
			(layer "F.Fab")
		)
		(pad "1" smd rect
			(at 0 0 90)
			(size 0.508 0.508)
			(layers "F.Cu" "F.Mask" "F.Paste")
			(net "P3V3_STBY")
		)
		(pad "2" smd rect
			(at 0 0.889 90)
			(size 0.508 0.508)
			(layers "F.Cu" "F.Mask" "F.Paste")
			(net "IRQ_BMC_PCH_NMI_STBY_N")
		)
		(zone
			(layer "F.Cu")
			(hatch none 0.5)
			(connect_pads
				(clearance 0)
			)
			(min_thickness 0.25)
			(keepout
				(tracks allowed)
				(vias not_allowed)
				(pads allowed)
				(copperpour not_allowed)
				(footprints allowed)
			)
			(placement
				(enabled no)
				(sheetname "")
			)
			(fill
				(thermal_gap 0.5)
				(thermal_bridge_width 0.5)
				(island_removal_mode 0)
			)
			(polygon
				(pts
					(xy 412.6865 -109.474) (xy 412.6865 -109.982) (xy 413.0675 -109.982) (xy 413.0675 -109.474)
				)
			)
		)
		(zone
			(layer "F.Cu")
			(hatch none 0.5)
			(connect_pads
				(clearance 0)
			)
			(min_thickness 0.25)
			(keepout
				(tracks not_allowed)
				(vias allowed)
				(pads allowed)
				(copperpour not_allowed)
				(footprints allowed)
			)
			(placement
				(enabled no)
				(sheetname "")
			)
			(fill
				(thermal_gap 0.5)
				(thermal_bridge_width 0.5)
				(island_removal_mode 0)
			)
			(polygon
				(pts
					(xy 413.0675 -109.474) (xy 413.0675 -109.982) (xy 412.6865 -109.982) (xy 412.6865 -109.474)
				)
			)
		)
	)
	(footprint ""
		(layer "F.Cu")
		(at 269.358872 -73.279)
		(property "Reference" "C5D51"
			(at 0 0 0)
			(layer "F.SilkS")
			(hide yes)
			(effects
				(font
					(size 1.27 1.27)
				)
			)
		)
		(property "Value" ""
			(at 0 0 0)
			(layer "F.Fab")
			(effects
				(font
					(size 1.27 1.27)
				)
			)
		)
		(duplicate_pad_numbers_are_jumpers no)
		(fp_poly
			(pts
				(xy -0.4953 -0.2032) (xy 0.4953 -0.2032) (xy 0.4953 1.6002) (xy -0.4953 1.6002)
			)
			(stroke
				(width 0)
				(type default)
			)
			(fill no)
			(layer "F.CrtYd")
		)
		(fp_line
			(start -0.4953 -0.2032)
			(end 0.4953 -0.2032)
			(stroke
				(width 0.1)
				(type default)
			)
			(layer "F.Fab")
		)
		(fp_line
			(start -0.4953 1.6002)
			(end -0.4953 -0.2032)
			(stroke
				(width 0.1)
				(type default)
			)
			(layer "F.Fab")
		)
		(fp_line
			(start 0.4953 -0.2032)
			(end 0.4953 1.6002)
			(stroke
				(width 0.1)
				(type default)
			)
			(layer "F.Fab")
		)
		(fp_line
			(start 0.4953 1.6002)
			(end -0.4953 1.6002)
			(stroke
				(width 0.1)
				(type default)
			)
			(layer "F.Fab")
		)
		(pad "1" smd rect
			(at 0 0)
			(size 0.762 0.889)
			(layers "F.Cu" "F.Mask" "F.Paste")
			(net "PVCCMCP_CPU0")
		)
		(pad "2" smd rect
			(at 0 1.397)
			(size 0.762 0.889)
			(layers "F.Cu" "F.Mask" "F.Paste")
			(net "GND")
		)
		(zone
			(layer "F.Cu")
			(hatch none 0.5)
			(connect_pads
				(clearance 0)
			)
			(min_thickness 0.25)
			(keepout
				(tracks not_allowed)
				(vias allowed)
				(pads allowed)
				(copperpour not_allowed)
				(footprints allowed)
			)
			(placement
				(enabled no)
				(sheetname "")
			)
			(fill
				(thermal_gap 0.5)
				(thermal_bridge_width 0.5)
				(island_removal_mode 0)
			)
			(polygon
				(pts
					(xy 268.977872 -72.8345) (xy 269.739872 -72.8345) (xy 269.739872 -72.3265) (xy 268.977872 -72.3265)
				)
			)
		)
	)
	(footprint ""
		(layer "F.Cu")
		(at 401.066 -45.4025 180)
		(property "Reference" "R7F3"
			(at 0 0 180)
			(layer "F.SilkS")
			(hide yes)
			(effects
				(font
					(size 1.27 1.27)
				)
			)
		)
		(property "Value" ""
			(at 0 0 180)
			(layer "F.Fab")
			(effects
				(font
					(size 1.27 1.27)
				)
			)
		)
		(duplicate_pad_numbers_are_jumpers no)
		(fp_poly
			(pts
				(xy -0.2794 -0.1016) (xy 0.2794 -0.1016) (xy 0.2794 0.9906) (xy -0.2794 0.9906)
			)
			(stroke
				(width 0)
				(type default)
			)
			(fill no)
			(layer "F.CrtYd")
		)
		(fp_line
			(start 0.2794 0.9906)
			(end 0.2794 -0.1016)
			(stroke
				(width 0.1)
				(type default)
			)
			(layer "F.Fab")
		)
		(fp_line
			(start 0.2794 -0.1016)
			(end -0.2794 -0.1016)
			(stroke
				(width 0.1)
				(type default)
			)
			(layer "F.Fab")
		)
		(fp_line
			(start -0.2794 0.9906)
			(end 0.2794 0.9906)
			(stroke
				(width 0.1)
				(type default)
			)
			(layer "F.Fab")
		)
		(fp_line
			(start -0.2794 -0.1016)
			(end -0.2794 0.9906)
			(stroke
				(width 0.1)
				(type default)
			)
			(layer "F.Fab")
		)
		(pad "1" smd rect
			(at 0 0 180)
			(size 0.508 0.508)
			(layers "F.Cu" "F.Mask" "F.Paste")
			(net "SPI_BIOS_SOCKET_IO3")
		)
		(pad "2" smd rect
			(at 0 0.889 180)
			(size 0.508 0.508)
			(layers "F.Cu" "F.Mask" "F.Paste")
			(net "PU_BIOS_SPI_HOLD0_N")
		)
		(zone
			(layer "F.Cu")
			(hatch none 0.5)
			(connect_pads
				(clearance 0)
			)
			(min_thickness 0.25)
			(keepout
				(tracks not_allowed)
				(vias allowed)
				(pads allowed)
				(copperpour not_allowed)
				(footprints allowed)
			)
			(placement
				(enabled no)
				(sheetname "")
			)
			(fill
				(thermal_gap 0.5)
				(thermal_bridge_width 0.5)
				(island_removal_mode 0)
			)
			(polygon
				(pts
					(xy 401.32 -46.0375) (xy 400.812 -46.0375) (xy 400.812 -45.6565) (xy 401.32 -45.6565)
				)
			)
		)
		(zone
			(layer "F.Cu")
			(hatch none 0.5)
			(connect_pads
				(clearance 0)
			)
			(min_thickness 0.25)
			(keepout
				(tracks allowed)
				(vias not_allowed)
				(pads allowed)
				(copperpour not_allowed)
				(footprints allowed)
			)
			(placement
				(enabled no)
				(sheetname "")
			)
			(fill
				(thermal_gap 0.5)
				(thermal_bridge_width 0.5)
				(island_removal_mode 0)
			)
			(polygon
				(pts
					(xy 401.32 -45.6565) (xy 400.812 -45.6565) (xy 400.812 -46.0375) (xy 401.32 -46.0375)
				)
			)
		)
	)
)
